(kicad_pcb
	(version 20260206)
	(generator "pcbnew")
	(generator_version "10.0")
	(general
		(thickness 1.6)
		(legacy_teardrops no)
	)
	(paper "A4")
	(title_block
		(title "04192023_DAF0TMB3IC0_F0TG_MB_C_brd_V02_OCP.brd")
		(comment 1 "Grand Teton / footprints 3098-3101 of 8354")
	)
	(layers
		(0 "F.Cu" signal "TOP")
		(4 "In1.Cu" signal "GND")
		(6 "In2.Cu" signal "IN1")
		(8 "In3.Cu" signal "GND1")
		(10 "In4.Cu" signal "IN2")
		(12 "In5.Cu" signal "GND2")
		(14 "In6.Cu" signal "IN3")
		(16 "In7.Cu" signal "GND3")
		(18 "In8.Cu" signal "VCC")
		(20 "In9.Cu" signal "VCC1")
		(22 "In10.Cu" signal "GND4")
		(24 "In11.Cu" signal "IN4")
		(26 "In12.Cu" signal "GND5")
		(28 "In13.Cu" signal "IN5")
		(30 "In14.Cu" signal "GND6")
		(32 "In15.Cu" signal "IN6")
		(34 "In16.Cu" signal "GND7")
		(2 "B.Cu" signal "BOTTOM")
		(9 "F.Adhes" user "F.Adhesive")
		(11 "B.Adhes" user "B.Adhesive")
		(13 "F.Paste" user "Package Geometry/Pastemask Top")
		(15 "B.Paste" user "Package Geometry/Pastemask Bottom")
		(5 "F.SilkS" user "Ref Des/Silkscreen Top")
		(7 "B.SilkS" user "Ref Des/Silkscreen Bottom")
		(1 "F.Mask" user "Board Geometry/Soldermask Top")
		(3 "B.Mask" user "Board Geometry/Soldermask Bottom")
		(17 "Dwgs.User" user "User.Drawings")
		(19 "Cmts.User" user "User.Comments")
		(21 "Eco1.User" user "User.Eco1")
		(23 "Eco2.User" user "User.Eco2")
		(25 "Edge.Cuts" user "Board Geometry/Outline")
		(27 "Margin" user)
		(31 "F.CrtYd" user "Package Geometry/Place Bound Top")
		(29 "B.CrtYd" user "Package Geometry/Place Bound Bottom")
		(35 "F.Fab" user "Ref Des/Assembly Top")
		(33 "B.Fab" user "Ref Des/Assembly Bottom")
	)
	(footprint ""
		(layer "F.Cu")
		(at 67.021964 -149.721316 -90)
		(property "Reference" "PR8002"
			(at 0 0 270)
			(layer "F.SilkS")
			(hide yes)
			(effects
				(font
					(size 1.27 1.27)
				)
			)
		)
		(property "Value" ""
			(at 0 0 270)
			(layer "F.Fab")
			(effects
				(font
					(size 1.27 1.27)
				)
			)
		)
		(duplicate_pad_numbers_are_jumpers no)
		(fp_line
			(start -0.7874 0.4064)
			(end -0.7874 -0.4064)
			(stroke
				(width 0.1524)
				(type default)
			)
			(layer "F.SilkS")
		)
		(fp_line
			(start 0.7874 0.4064)
			(end -0.7874 0.4064)
			(stroke
				(width 0.1524)
				(type default)
			)
			(layer "F.SilkS")
		)
		(fp_line
			(start -0.7874 -0.4064)
			(end 0.7874 -0.4064)
			(stroke
				(width 0.1524)
				(type default)
			)
			(layer "F.SilkS")
		)
		(fp_line
			(start 0.7874 -0.4064)
			(end 0.7874 0.4064)
			(stroke
				(width 0.1524)
				(type default)
			)
			(layer "F.SilkS")
		)
		(fp_line
			(start -0.67945 0.3048)
			(end -0.67945 -0.305054)
			(stroke
				(width 0.1)
				(type default)
			)
			(layer "F.Fab")
		)
		(fp_line
			(start -0.12065 0.3048)
			(end -0.67945 0.3048)
			(stroke
				(width 0.1)
				(type default)
			)
			(layer "F.Fab")
		)
		(fp_line
			(start 0.120396 0.3048)
			(end 0.120396 0.2794)
			(stroke
				(width 0.1)
				(type default)
			)
			(layer "F.Fab")
		)
		(fp_line
			(start 0.67945 0.3048)
			(end 0.120396 0.3048)
			(stroke
				(width 0.1)
				(type default)
			)
			(layer "F.Fab")
		)
		(fp_line
			(start -0.12065 0.2794)
			(end -0.12065 0.3048)
			(stroke
				(width 0.1)
				(type default)
			)
			(layer "F.Fab")
		)
		(fp_line
			(start 0.120396 0.2794)
			(end -0.12065 0.2794)
			(stroke
				(width 0.1)
				(type default)
			)
			(layer "F.Fab")
		)
		(fp_line
			(start -0.12065 -0.2794)
			(end 0.12065 -0.2794)
			(stroke
				(width 0.1)
				(type default)
			)
			(layer "F.Fab")
		)
		(fp_line
			(start 0.12065 -0.2794)
			(end 0.12065 -0.3048)
			(stroke
				(width 0.1)
				(type default)
			)
			(layer "F.Fab")
		)
		(fp_line
			(start 0.12065 -0.3048)
			(end 0.67945 -0.3048)
			(stroke
				(width 0.1)
				(type default)
			)
			(layer "F.Fab")
		)
		(fp_line
			(start 0.67945 -0.3048)
			(end 0.67945 0.3048)
			(stroke
				(width 0.1)
				(type default)
			)
			(layer "F.Fab")
		)
		(fp_line
			(start -0.67945 -0.305054)
			(end -0.12065 -0.305054)
			(stroke
				(width 0.1)
				(type default)
			)
			(layer "F.Fab")
		)
		(fp_line
			(start -0.12065 -0.305054)
			(end -0.12065 -0.2794)
			(stroke
				(width 0.1)
				(type default)
			)
			(layer "F.Fab")
		)
		(pad "1" smd circle
			(at -0.40005 0 270)
			(size 0 0)
			(layers "F.Cu" "F.Mask" "F.Paste")
			(net "SW_PVDD18_S5_P1_BST")
		)
		(pad "2" smd circle
			(at 0.40005 0 270)
			(size 0 0)
			(layers "F.Cu" "F.Mask" "F.Paste")
			(net "SW_PVDD18_S5_P1_BST_R")
		)
	)
	(footprint ""
		(layer "F.Cu")
		(at 225.429826 -388.160514 -90)
		(property "Reference" "H6002"
			(at 0.127 -6.738112 90)
			(unlocked yes)
			(layer "F.SilkS")
			(effects
				(font
					(size 0.7874 0.5842)
					(thickness 0.1524)
				)
				(justify left)
			)
		)
		(property "Value" ""
			(at 0 0 270)
			(layer "F.Fab")
			(effects
				(font
					(size 1.27 1.27)
				)
			)
		)
		(duplicate_pad_numbers_are_jumpers no)
		(pad "1" thru_hole circle
			(at 0 0 270)
			(size 8.001 8.001)
			(drill 4.2164)
			(layers "*.Cu" "*.Mask")
			(remove_unused_layers no)
			(net "GND")
			(clearance -1.6383)
		)
	)
	(footprint ""
		(layer "F.Cu")
		(at 82.28457 -182.743856 180)
		(property "Reference" "PU4"
			(at -0.19812 -6.65861 0)
			(unlocked yes)
			(layer "F.SilkS")
			(effects
				(font
					(size 0.7874 0.5842)
					(thickness 0.1524)
				)
				(justify left)
			)
		)
		(property "Value" ""
			(at 0 0 180)
			(layer "F.Fab")
			(effects
				(font
					(size 1.27 1.27)
				)
			)
		)
		(duplicate_pad_numbers_are_jumpers no)
		(fp_line
			(start 2.500122 2.999994)
			(end 2.2987 2.999994)
			(stroke
				(width 0.1524)
				(type default)
			)
			(layer "F.SilkS")
		)
		(fp_line
			(start 2.500122 2.339594)
			(end 2.500122 2.999994)
			(stroke
				(width 0.1524)
				(type default)
			)
			(layer "F.SilkS")
		)
		(fp_line
			(start 2.500122 -2.999994)
			(end 2.500122 -2.44348)
			(stroke
				(width 0.1524)
				(type default)
			)
			(layer "F.SilkS")
		)
		(fp_line
			(start 2.31394 -2.999994)
			(end 2.500122 -2.999994)
			(stroke
				(width 0.1524)
				(type default)
			)
			(layer "F.SilkS")
		)
		(fp_line
			(start -2.2987 2.999994)
			(end -2.500122 2.999994)
			(stroke
				(width 0.1524)
				(type default)
			)
			(layer "F.SilkS")
		)
		(fp_line
			(start -2.500122 2.999994)
			(end -2.500122 2.339594)
			(stroke
				(width 0.1524)
				(type default)
			)
			(layer "F.SilkS")
		)
		(fp_line
			(start -2.500122 0.6604)
			(end -2.500122 0.229108)
			(stroke
				(width 0.1524)
				(type default)
			)
			(layer "F.SilkS")
		)
		(fp_line
			(start -2.500122 -2.529078)
			(end -2.500122 -2.999994)
			(stroke
				(width 0.1524)
				(type default)
			)
			(layer "F.SilkS")
		)
		(fp_line
			(start -2.500122 -2.999994)
			(end -2.24409 -2.999994)
			(stroke
				(width 0.1524)
				(type default)
			)
			(layer "F.SilkS")
		)
		(fp_poly
			(pts
				(xy -2.612898 -2.543556) (xy -3.380232 -2.799334) (xy -2.868676 -3.31089)
			)
			(stroke
				(width 0)
				(type default)
			)
			(fill yes)
			(layer "F.SilkS")
		)
		(fp_line
			(start 2.500122 2.999994)
			(end -2.500122 2.999994)
			(stroke
				(width 0.1)
				(type default)
			)
			(layer "F.Fab")
		)
		(fp_line
			(start 2.500122 -2.999994)
			(end 2.500122 2.999994)
			(stroke
				(width 0.1)
				(type default)
			)
			(layer "F.Fab")
		)
		(fp_line
			(start -2.500122 2.999994)
			(end -2.500122 -2.999994)
			(stroke
				(width 0.1)
				(type default)
			)
			(layer "F.Fab")
		)
		(fp_line
			(start -2.500122 -2.999994)
			(end 2.500122 -2.999994)
			(stroke
				(width 0.1)
				(type default)
			)
			(layer "F.Fab")
		)
		(fp_poly
			(pts
				(xy -4.218432 -2.783078) (xy -4.218432 -1.767078) (xy -3.202432 -2.275078)
			)
			(stroke
				(width 0)
				(type default)
			)
			(fill yes)
			(layer "F.Fab")
		)
		(pad "1" smd rect
			(at -2.400046 -2.275078 270)
			(size 0.2286 0.6096)
			(layers "F.Cu" "F.Mask" "F.Paste")
			(net "PVDDCR_CPU0_P1_VOS1")
		)
		(pad "2" smd rect
			(at -2.400046 -1.82499 270)
			(size 0.2286 0.6096)
			(layers "F.Cu" "F.Mask" "F.Paste")
			(net "GND")
		)
		(pad "3" smd rect
			(at -2.400046 -1.374902 270)
			(size 0.2286 0.6096)
			(layers "F.Cu" "F.Mask" "F.Paste")
			(net "PVDDCR_CPU0_P1_VCC1")
		)
		(pad "4" smd rect
			(at -2.400046 -0.925068 270)
			(size 0.2286 0.6096)
			(layers "F.Cu" "F.Mask" "F.Paste")
			(net "PVDDCR_CPU0_P1_PVCC")
		)
		(pad "5" smd rect
			(at -2.400046 -0.47498 270)
			(size 0.2286 0.6096)
			(layers "F.Cu" "F.Mask" "F.Paste")
			(net "GND")
		)
		(pad "6" smd rect
			(at -2.400046 -0.024892 270)
			(size 0.2286 0.6096)
			(layers "F.Cu" "F.Mask" "F.Paste")
			(net "NC_PVDDCR_CPU0_P1_GL1_1")
		)
		(pad "7_9-20_24" smd circle
			(at 0 1.150112 270)
			(size 0 0)
			(layers "F.Cu" "F.Mask" "F.Paste")
			(net "GND")
		)
		(pad "10_19" smd rect
			(at 0 2.899918 270)
			(size 0.6096 4.318)
			(layers "F.Cu" "F.Mask" "F.Paste")
			(net "SW_PVDDCR_CPU0_P1_SW1")
		)
		(pad "25_29" smd rect
			(at 1.549908 -1.279906 90)
			(size 2.0574 2.3114)
			(layers "F.Cu" "F.Mask" "F.Paste")
			(net "SW_P12V_AUX_PVDDCR_CPU0_P1_FLT")
		)
		(pad "30" smd rect
			(at 2.05994 -2.899918 180)
			(size 0.2286 0.6096)
			(layers "F.Cu" "F.Mask" "F.Paste")
			(net "SW_P12V_AUX_PVDDCR_CPU0_P1_FLT")
		)
		(pad "31" smd rect
			(at 1.610106 -2.899918 180)
			(size 0.2286 0.6096)
			(layers "F.Cu" "F.Mask" "F.Paste")
			(net "NC_PVDDCR_CPU0_P1_DNC1")
		)
		(pad "32" smd rect
			(at 1.160018 -2.899918 180)
			(size 0.2286 0.6096)
			(layers "F.Cu" "F.Mask" "F.Paste")
			(net "SW_PVDDCR_CPU0_P1_PH1")
		)
		(pad "33" smd rect
			(at 0.70993 -2.899918 180)
			(size 0.2286 0.6096)
			(layers "F.Cu" "F.Mask" "F.Paste")
			(net "SW_PVDDCR_CPU0_P1_BOOT1")
		)
		(pad "34" smd rect
			(at 0.260096 -2.899918 180)
			(size 0.2286 0.6096)
			(layers "F.Cu" "F.Mask" "F.Paste")
			(net "PVDDCR_CPU0_P1_PWM1")
		)
		(pad "35" smd rect
			(at -0.189992 -2.899918 180)
			(size 0.2286 0.6096)
			(layers "F.Cu" "F.Mask" "F.Paste")
			(net "PVDDCR_CPU0_P1_VCC1")
		)
		(pad "36" smd rect
			(at -0.64008 -2.899918 180)
			(size 0.2286 0.6096)
			(layers "F.Cu" "F.Mask" "F.Paste")
			(net "PVDDCR_CPU0_P1_TEMP0")
		)
		(pad "37" smd rect
			(at -1.089914 -2.899918 180)
			(size 0.2286 0.6096)
			(layers "F.Cu" "F.Mask" "F.Paste")
			(net "PVDDCR_CPU0_P1_LSET1")
		)
		(pad "38" smd rect
			(at -1.540002 -2.899918 180)
			(size 0.2286 0.6096)
			(layers "F.Cu" "F.Mask" "F.Paste")
			(net "PVDDCR_CPU0_P1_IMON1")
		)
		(pad "39" smd rect
			(at -1.99009 -2.899918 180)
			(size 0.2286 0.6096)
			(layers "F.Cu" "F.Mask" "F.Paste")
			(net "PVDDCR_CPU0_P1_VCCS")
		)
		(pad "40" smd rect
			(at -0.87503 -1.27508 180)
			(size 1.7526 1.9558)
			(layers "F.Cu" "F.Mask" "F.Paste")
			(net "GND")
		)
		(pad "41" smd rect
			(at -1.525016 0.249936 90)
			(size 0.3048 0.4572)
			(layers "F.Cu" "F.Mask" "F.Paste")
			(net "NC_PVDDCR_CPU0_P1_GL2_1")
		)
		(zone
			(layer "F.Cu")
			(hatch none 0.5)
			(connect_pads
				(clearance 0)
			)
			(min_thickness 0.25)
			(keepout
				(tracks not_allowed)
				(vias allowed)
				(pads allowed)
				(copperpour not_allowed)
				(footprints allowed)
			)
			(placement
				(enabled no)
				(sheetname "")
			)
			(fill
				(thermal_gap 0.5)
				(thermal_bridge_width 0.5)
				(island_removal_mode 0)
			)
			(polygon
				(pts
					(xy 84.784692 -185.288174) (xy 84.784692 -184.99455) (xy 79.784448 -184.99455) (xy 79.784448 -185.288174)
					(xy 80.07477 -185.288174) (xy 84.49437 -185.288174)
				)
			)
		)
		(zone
			(layer "F.Cu")
			(hatch none 0.5)
			(connect_pads
				(clearance 0)
			)
			(min_thickness 0.25)
			(keepout
				(tracks not_allowed)
				(vias allowed)
				(pads allowed)
				(copperpour not_allowed)
				(footprints allowed)
			)
			(placement
				(enabled no)
				(sheetname "")
			)
			(fill
				(thermal_gap 0.5)
				(thermal_bridge_width 0.5)
				(island_removal_mode 0)
			)
			(polygon
				(pts
					(xy 82.2325 -182.497476) (xy 82.2325 -180.440076) (xy 84.0867 -180.440076) (xy 84.0867 -180.681122)
					(xy 84.329016 -180.681122) (xy 84.329016 -180.199538) (xy 80.431386 -180.199538) (xy 80.431386 -180.38445)
					(xy 81.941162 -180.38445) (xy 81.941162 -182.54345) (xy 79.784448 -182.54345) (xy 79.784448 -182.793132)
					(xy 81.936844 -182.793132)
				)
			)
		)
	)
	(footprint ""
		(layer "F.Cu")
		(at 414.84804 -378.95403 -90)
		(property "Reference" "C850"
			(at 0 0 270)
			(layer "F.SilkS")
			(hide yes)
			(effects
				(font
					(size 1.27 1.27)
				)
			)
		)
		(property "Value" ""
			(at 0 0 270)
			(layer "F.Fab")
			(effects
				(font
					(size 1.27 1.27)
				)
			)
		)
		(duplicate_pad_numbers_are_jumpers no)
		(fp_line
			(start -0.299974 0.150114)
			(end -0.299974 -0.150114)
			(stroke
				(width 0.1)
				(type default)
			)
			(layer "F.Fab")
		)
		(fp_line
			(start 0.299974 0.150114)
			(end -0.299974 0.150114)
			(stroke
				(width 0.1)
				(type default)
			)
			(layer "F.Fab")
		)
		(fp_line
			(start -0.299974 -0.150114)
			(end 0.299974 -0.150114)
			(stroke
				(width 0.1)
				(type default)
			)
			(layer "F.Fab")
		)
		(fp_line
			(start 0.299974 -0.150114)
			(end 0.299974 0.150114)
			(stroke
				(width 0.1)
				(type default)
			)
			(layer "F.Fab")
		)
		(pad "1" smd rect
			(at -0.2667 0 270)
			(size 0.3048 0.381)
			(layers "F.Cu" "F.Mask" "F.Paste")
			(net "P5E_CPU0_P2_TX_C_DN<9>")
		)
		(pad "2" smd rect
			(at 0.2667 0 270)
			(size 0.3048 0.381)
			(layers "F.Cu" "F.Mask" "F.Paste")
			(net "P5E_CPU0_P2_TX_DN<9>")
		)
	)
)
